(kicad_pcb
	(version 20260206)
	(generator "pcbnew")
	(generator_version "10.0")
	(general
		(thickness 1.6)
		(legacy_teardrops no)
	)
	(paper "A4")
	(title_block
		(title "01162023_DA0F0TEBIF0_F0T_Expander_BD_F_brd_V02_OCP.brd")
		(comment 1 "Grand Teton / footprints 561-566 of 9728")
	)
	(layers
		(0 "F.Cu" signal "TOP")
		(4 "In1.Cu" signal "GND")
		(6 "In2.Cu" signal "VCC")
		(8 "In3.Cu" signal "VCC1")
		(10 "In4.Cu" signal "GND1")
		(12 "In5.Cu" signal "IN1")
		(14 "In6.Cu" signal "GND2")
		(16 "In7.Cu" signal "IN2")
		(18 "In8.Cu" signal "GND3")
		(20 "In9.Cu" signal "IN3")
		(22 "In10.Cu" signal "GND4")
		(24 "In11.Cu" signal "IN4")
		(26 "In12.Cu" signal "GND5")
		(28 "In13.Cu" signal "IN5")
		(30 "In14.Cu" signal "GND6")
		(32 "In15.Cu" signal "IN6")
		(34 "In16.Cu" signal "GND7")
		(2 "B.Cu" signal "BOTTOM")
		(9 "F.Adhes" user "F.Adhesive")
		(11 "B.Adhes" user "B.Adhesive")
		(13 "F.Paste" user "Package Geometry/Pastemask Top")
		(15 "B.Paste" user "Package Geometry/Pastemask Bottom")
		(5 "F.SilkS" user "Ref Des/Silkscreen Top")
		(7 "B.SilkS" user "Ref Des/Silkscreen Bottom")
		(1 "F.Mask" user "Board Geometry/Soldermask Top")
		(3 "B.Mask" user "Board Geometry/Soldermask Bottom")
		(17 "Dwgs.User" user "User.Drawings")
		(19 "Cmts.User" user "User.Comments")
		(21 "Eco1.User" user "User.Eco1")
		(23 "Eco2.User" user "User.Eco2")
		(25 "Edge.Cuts" user "Board Geometry/Outline")
		(27 "Margin" user)
		(31 "F.CrtYd" user "Package Geometry/Place Bound Top")
		(29 "B.CrtYd" user "Package Geometry/Place Bound Bottom")
		(35 "F.Fab" user "Ref Des/Assembly Top")
		(33 "B.Fab" user "Ref Des/Assembly Bottom")
	)
	(footprint ""
		(layer "F.Cu")
		(at 232.9815 -140.49248 90)
		(property "Reference" "R4185"
			(at 0 0 90)
			(layer "F.SilkS")
			(hide yes)
			(effects
				(font
					(size 1.27 1.27)
				)
			)
		)
		(property "Value" ""
			(at 0 0 90)
			(layer "F.Fab")
			(effects
				(font
					(size 1.27 1.27)
				)
			)
		)
		(duplicate_pad_numbers_are_jumpers no)
		(fp_line
			(start 0.7874 -0.4064)
			(end 0.7874 0.4064)
			(stroke
				(width 0.1524)
				(type default)
			)
			(layer "F.SilkS")
		)
		(fp_line
			(start -0.7874 -0.4064)
			(end 0.7874 -0.4064)
			(stroke
				(width 0.1524)
				(type default)
			)
			(layer "F.SilkS")
		)
		(fp_line
			(start 0.7874 0.4064)
			(end -0.7874 0.4064)
			(stroke
				(width 0.1524)
				(type default)
			)
			(layer "F.SilkS")
		)
		(fp_line
			(start -0.7874 0.4064)
			(end -0.7874 -0.4064)
			(stroke
				(width 0.1524)
				(type default)
			)
			(layer "F.SilkS")
		)
		(fp_line
			(start -0.12065 -0.305054)
			(end -0.12065 -0.2794)
			(stroke
				(width 0.1)
				(type default)
			)
			(layer "F.Fab")
		)
		(fp_line
			(start -0.67945 -0.305054)
			(end -0.12065 -0.305054)
			(stroke
				(width 0.1)
				(type default)
			)
			(layer "F.Fab")
		)
		(fp_line
			(start 0.67945 -0.3048)
			(end 0.67945 0.3048)
			(stroke
				(width 0.1)
				(type default)
			)
			(layer "F.Fab")
		)
		(fp_line
			(start 0.12065 -0.3048)
			(end 0.67945 -0.3048)
			(stroke
				(width 0.1)
				(type default)
			)
			(layer "F.Fab")
		)
		(fp_line
			(start 0.12065 -0.2794)
			(end 0.12065 -0.3048)
			(stroke
				(width 0.1)
				(type default)
			)
			(layer "F.Fab")
		)
		(fp_line
			(start -0.12065 -0.2794)
			(end 0.12065 -0.2794)
			(stroke
				(width 0.1)
				(type default)
			)
			(layer "F.Fab")
		)
		(fp_line
			(start 0.120396 0.2794)
			(end -0.12065 0.2794)
			(stroke
				(width 0.1)
				(type default)
			)
			(layer "F.Fab")
		)
		(fp_line
			(start -0.12065 0.2794)
			(end -0.12065 0.3048)
			(stroke
				(width 0.1)
				(type default)
			)
			(layer "F.Fab")
		)
		(fp_line
			(start 0.67945 0.3048)
			(end 0.120396 0.3048)
			(stroke
				(width 0.1)
				(type default)
			)
			(layer "F.Fab")
		)
		(fp_line
			(start 0.120396 0.3048)
			(end 0.120396 0.2794)
			(stroke
				(width 0.1)
				(type default)
			)
			(layer "F.Fab")
		)
		(fp_line
			(start -0.12065 0.3048)
			(end -0.67945 0.3048)
			(stroke
				(width 0.1)
				(type default)
			)
			(layer "F.Fab")
		)
		(fp_line
			(start -0.67945 0.3048)
			(end -0.67945 -0.305054)
			(stroke
				(width 0.1)
				(type default)
			)
			(layer "F.Fab")
		)
		(pad "1" smd circle
			(at -0.40005 0 90)
			(size 0 0)
			(layers "F.Cu" "F.Mask" "F.Paste")
			(net "XTAL_CK440_PEX_25M_R_XIN")
		)
		(pad "2" smd circle
			(at 0.40005 0 90)
			(size 0 0)
			(layers "F.Cu" "F.Mask" "F.Paste")
			(net "XTAL_CK440_PEX_25M_XIN")
		)
	)
	(footprint ""
		(layer "F.Cu")
		(at 149.140164 -259.834634 180)
		(property "Reference" "C3222"
			(at 0 0 180)
			(layer "F.SilkS")
			(hide yes)
			(effects
				(font
					(size 1.27 1.27)
				)
			)
		)
		(property "Value" ""
			(at 0 0 180)
			(layer "F.Fab")
			(effects
				(font
					(size 1.27 1.27)
				)
			)
		)
		(duplicate_pad_numbers_are_jumpers no)
		(fp_line
			(start 1.2954 0.5842)
			(end -1.2954 0.5842)
			(stroke
				(width 0.1524)
				(type default)
			)
			(layer "F.SilkS")
		)
		(fp_line
			(start 1.2954 -0.5842)
			(end 1.2954 0.5842)
			(stroke
				(width 0.1524)
				(type default)
			)
			(layer "F.SilkS")
		)
		(fp_line
			(start -1.2954 0.5842)
			(end -1.2954 -0.5842)
			(stroke
				(width 0.1524)
				(type default)
			)
			(layer "F.SilkS")
		)
		(fp_line
			(start -1.2954 -0.5842)
			(end 1.2954 -0.5842)
			(stroke
				(width 0.1524)
				(type default)
			)
			(layer "F.SilkS")
		)
		(fp_line
			(start 1.1938 0.4064)
			(end 0.8636 0.4064)
			(stroke
				(width 0.1)
				(type default)
			)
			(layer "F.Fab")
		)
		(fp_line
			(start 1.1938 -0.4064)
			(end 1.1938 0.4064)
			(stroke
				(width 0.1)
				(type default)
			)
			(layer "F.Fab")
		)
		(fp_line
			(start 0.8636 0.4572)
			(end -0.8636 0.4572)
			(stroke
				(width 0.1)
				(type default)
			)
			(layer "F.Fab")
		)
		(fp_line
			(start 0.8636 0.4064)
			(end 0.8636 0.4572)
			(stroke
				(width 0.1)
				(type default)
			)
			(layer "F.Fab")
		)
		(fp_line
			(start 0.8636 -0.4064)
			(end 1.1938 -0.4064)
			(stroke
				(width 0.1)
				(type default)
			)
			(layer "F.Fab")
		)
		(fp_line
			(start 0.8636 -0.4572)
			(end 0.8636 -0.4064)
			(stroke
				(width 0.1)
				(type default)
			)
			(layer "F.Fab")
		)
		(fp_line
			(start -0.8636 0.4572)
			(end -0.8636 0.4064)
			(stroke
				(width 0.1)
				(type default)
			)
			(layer "F.Fab")
		)
		(fp_line
			(start -0.8636 0.4064)
			(end -1.1938 0.4064)
			(stroke
				(width 0.1)
				(type default)
			)
			(layer "F.Fab")
		)
		(fp_line
			(start -0.8636 -0.4064)
			(end -0.8636 -0.4572)
			(stroke
				(width 0.1)
				(type default)
			)
			(layer "F.Fab")
		)
		(fp_line
			(start -0.8636 -0.4572)
			(end 0.8636 -0.4572)
			(stroke
				(width 0.1)
				(type default)
			)
			(layer "F.Fab")
		)
		(fp_line
			(start -1.1938 0.4064)
			(end -1.1938 -0.4064)
			(stroke
				(width 0.1)
				(type default)
			)
			(layer "F.Fab")
		)
		(fp_line
			(start -1.1938 -0.4064)
			(end -0.8636 -0.4064)
			(stroke
				(width 0.1)
				(type default)
			)
			(layer "F.Fab")
		)
		(pad "1" smd rect
			(at -0.7366 0 90)
			(size 0.7112 0.8128)
			(layers "F.Cu" "F.Mask" "F.Paste")
			(net "PCEPLL3_VDDA18_PEX1_R")
		)
		(pad "2" smd rect
			(at 0.7366 0 90)
			(size 0.7112 0.8128)
			(layers "F.Cu" "F.Mask" "F.Paste")
			(net "GND")
		)
	)
	(footprint ""
		(layer "F.Cu")
		(at 153.153872 -147.969224 90)
		(property "Reference" "C876"
			(at 0 0 90)
			(layer "F.SilkS")
			(hide yes)
			(effects
				(font
					(size 1.27 1.27)
				)
			)
		)
		(property "Value" ""
			(at 0 0 90)
			(layer "F.Fab")
			(effects
				(font
					(size 1.27 1.27)
				)
			)
		)
		(duplicate_pad_numbers_are_jumpers no)
		(fp_line
			(start 1.524 -0.762)
			(end 1.524 0.762)
			(stroke
				(width 0.1524)
				(type default)
			)
			(layer "F.SilkS")
		)
		(fp_line
			(start -1.524 -0.762)
			(end 1.524 -0.762)
			(stroke
				(width 0.1524)
				(type default)
			)
			(layer "F.SilkS")
		)
		(fp_line
			(start 1.524 0.762)
			(end -1.524 0.762)
			(stroke
				(width 0.1524)
				(type default)
			)
			(layer "F.SilkS")
		)
		(fp_line
			(start -1.524 0.762)
			(end -1.524 -0.762)
			(stroke
				(width 0.1524)
				(type default)
			)
			(layer "F.SilkS")
		)
		(fp_line
			(start 1.1049 -0.724916)
			(end -1.1049 -0.724916)
			(stroke
				(width 0.1)
				(type default)
			)
			(layer "F.Fab")
		)
		(fp_line
			(start -1.1049 -0.724916)
			(end -1.1049 0.724916)
			(stroke
				(width 0.1)
				(type default)
			)
			(layer "F.Fab")
		)
		(fp_line
			(start 1.1049 0.724916)
			(end 1.1049 -0.724916)
			(stroke
				(width 0.1)
				(type default)
			)
			(layer "F.Fab")
		)
		(fp_line
			(start -1.1049 0.724916)
			(end 1.1049 0.724916)
			(stroke
				(width 0.1)
				(type default)
			)
			(layer "F.Fab")
		)
		(pad "1" smd rect
			(at -0.889 0 270)
			(size 1.016 1.27)
			(layers "F.Cu" "F.Mask" "F.Paste")
			(net "P12V_NIC2")
		)
		(pad "2" smd rect
			(at 0.889 0 270)
			(size 1.016 1.27)
			(layers "F.Cu" "F.Mask" "F.Paste")
			(net "GND")
		)
	)
	(footprint ""
		(layer "F.Cu")
		(at 10.14984 -148.872702)
		(property "Reference" "PD78"
			(at -3.4544 -2.225548 0)
			(unlocked yes)
			(layer "F.SilkS")
			(effects
				(font
					(size 0.7874 0.5842)
					(thickness 0.1524)
				)
				(justify left)
			)
		)
		(property "Value" ""
			(at 0 0 0)
			(layer "F.Fab")
			(effects
				(font
					(size 1.27 1.27)
				)
			)
		)
		(duplicate_pad_numbers_are_jumpers no)
		(fp_line
			(start -3.400044 -1.459992)
			(end 4.107942 -1.459992)
			(stroke
				(width 0.1524)
				(type default)
			)
			(layer "F.SilkS")
		)
		(fp_line
			(start -3.400044 1.459992)
			(end -3.400044 -1.459992)
			(stroke
				(width 0.1524)
				(type default)
			)
			(layer "F.SilkS")
		)
		(fp_line
			(start 4.107942 -1.459992)
			(end 4.107942 1.459992)
			(stroke
				(width 0.1524)
				(type default)
			)
			(layer "F.SilkS")
		)
		(fp_line
			(start 4.107942 1.459992)
			(end -3.400044 1.459992)
			(stroke
				(width 0.1524)
				(type default)
			)
			(layer "F.SilkS")
		)
		(fp_poly
			(pts
				(xy 4.107942 -1.459992) (xy 4.107942 1.459992) (xy 3.308096 1.459992) (xy 3.308096 -1.459992)
			)
			(stroke
				(width 0)
				(type default)
			)
			(fill yes)
			(layer "F.SilkS")
		)
		(fp_line
			(start -2.29997 -1.459992)
			(end 2.29997 -1.459992)
			(stroke
				(width 0.1)
				(type default)
			)
			(layer "F.Fab")
		)
		(fp_line
			(start -2.29997 1.459992)
			(end -2.29997 -1.459992)
			(stroke
				(width 0.1)
				(type default)
			)
			(layer "F.Fab")
		)
		(fp_line
			(start 2.29997 -1.459992)
			(end 2.29997 1.459992)
			(stroke
				(width 0.1)
				(type default)
			)
			(layer "F.Fab")
		)
		(fp_line
			(start 2.29997 1.459992)
			(end -2.29997 1.459992)
			(stroke
				(width 0.1)
				(type default)
			)
			(layer "F.Fab")
		)
		(fp_text user "+"
			(at -4.7752 -0.12065 0)
			(unlocked yes)
			(layer "F.SilkS")
			(effects
				(font
					(size 1.905 1.4224)
					(thickness 0.1524)
				)
				(justify left)
			)
		)
		(fp_text user "-"
			(at 5.4102 0.29845 180)
			(unlocked yes)
			(layer "F.SilkS")
			(effects
				(font
					(size 1.905 1.4224)
					(thickness 0.1524)
				)
				(justify left)
			)
		)
		(fp_text user "+"
			(at -4.7752 -0.12065 0)
			(unlocked yes)
			(layer "F.Fab")
			(effects
				(font
					(size 1.905 1.4224)
					(thickness 0.1524)
				)
				(justify left)
			)
		)
		(fp_text user "-"
			(at 5.4102 0.29845 180)
			(unlocked yes)
			(layer "F.Fab")
			(effects
				(font
					(size 1.905 1.4224)
					(thickness 0.1524)
				)
				(justify left)
			)
		)
		(pad "A" smd rect
			(at -1.999996 0 90)
			(size 1.7018 2.5146)
			(layers "F.Cu" "F.Mask" "F.Paste")
			(net "GND")
		)
		(pad "C" smd rect
			(at 1.999996 0 90)
			(size 1.7018 2.5146)
			(layers "F.Cu" "F.Mask" "F.Paste")
			(net "P12V_NIC0_R")
		)
	)
	(footprint ""
		(layer "F.Cu")
		(at 439.355484 -96.811592 -90)
		(property "Reference" "R761"
			(at 0 0 270)
			(layer "F.SilkS")
			(hide yes)
			(effects
				(font
					(size 1.27 1.27)
				)
			)
		)
		(property "Value" ""
			(at 0 0 270)
			(layer "F.Fab")
			(effects
				(font
					(size 1.27 1.27)
				)
			)
		)
		(duplicate_pad_numbers_are_jumpers no)
		(fp_line
			(start -0.7874 0.4064)
			(end -0.7874 -0.4064)
			(stroke
				(width 0.1524)
				(type default)
			)
			(layer "F.SilkS")
		)
		(fp_line
			(start 0.7874 0.4064)
			(end -0.7874 0.4064)
			(stroke
				(width 0.1524)
				(type default)
			)
			(layer "F.SilkS")
		)
		(fp_line
			(start -0.7874 -0.4064)
			(end 0.7874 -0.4064)
			(stroke
				(width 0.1524)
				(type default)
			)
			(layer "F.SilkS")
		)
		(fp_line
			(start 0.7874 -0.4064)
			(end 0.7874 0.4064)
			(stroke
				(width 0.1524)
				(type default)
			)
			(layer "F.SilkS")
		)
		(fp_line
			(start -0.67945 0.3048)
			(end -0.67945 -0.305054)
			(stroke
				(width 0.1)
				(type default)
			)
			(layer "F.Fab")
		)
		(fp_line
			(start -0.12065 0.3048)
			(end -0.67945 0.3048)
			(stroke
				(width 0.1)
				(type default)
			)
			(layer "F.Fab")
		)
		(fp_line
			(start 0.120396 0.3048)
			(end 0.120396 0.2794)
			(stroke
				(width 0.1)
				(type default)
			)
			(layer "F.Fab")
		)
		(fp_line
			(start 0.67945 0.3048)
			(end 0.120396 0.3048)
			(stroke
				(width 0.1)
				(type default)
			)
			(layer "F.Fab")
		)
		(fp_line
			(start -0.12065 0.2794)
			(end -0.12065 0.3048)
			(stroke
				(width 0.1)
				(type default)
			)
			(layer "F.Fab")
		)
		(fp_line
			(start 0.120396 0.2794)
			(end -0.12065 0.2794)
			(stroke
				(width 0.1)
				(type default)
			)
			(layer "F.Fab")
		)
		(fp_line
			(start -0.12065 -0.2794)
			(end 0.12065 -0.2794)
			(stroke
				(width 0.1)
				(type default)
			)
			(layer "F.Fab")
		)
		(fp_line
			(start 0.12065 -0.2794)
			(end 0.12065 -0.3048)
			(stroke
				(width 0.1)
				(type default)
			)
			(layer "F.Fab")
		)
		(fp_line
			(start 0.12065 -0.3048)
			(end 0.67945 -0.3048)
			(stroke
				(width 0.1)
				(type default)
			)
			(layer "F.Fab")
		)
		(fp_line
			(start 0.67945 -0.3048)
			(end 0.67945 0.3048)
			(stroke
				(width 0.1)
				(type default)
			)
			(layer "F.Fab")
		)
		(fp_line
			(start -0.67945 -0.305054)
			(end -0.12065 -0.305054)
			(stroke
				(width 0.1)
				(type default)
			)
			(layer "F.Fab")
		)
		(fp_line
			(start -0.12065 -0.305054)
			(end -0.12065 -0.2794)
			(stroke
				(width 0.1)
				(type default)
			)
			(layer "F.Fab")
		)
		(pad "1" smd circle
			(at -0.40005 0 270)
			(size 0 0)
			(layers "F.Cu" "F.Mask" "F.Paste")
			(net "NIC7_ADC_ALERT_N")
		)
		(pad "2" smd circle
			(at 0.40005 0 270)
			(size 0 0)
			(layers "F.Cu" "F.Mask" "F.Paste")
			(net "NIC_ADC_ALERT_N")
		)
	)
	(footprint ""
		(layer "F.Cu")
		(at 338.074 -154.686 180)
		(property "Reference" "R4817"
			(at 0 0 180)
			(layer "F.SilkS")
			(hide yes)
			(effects
				(font
					(size 1.27 1.27)
				)
			)
		)
		(property "Value" ""
			(at 0 0 180)
			(layer "F.Fab")
			(effects
				(font
					(size 1.27 1.27)
				)
			)
		)
		(duplicate_pad_numbers_are_jumpers no)
		(fp_line
			(start 0.7874 0.4064)
			(end -0.7874 0.4064)
			(stroke
				(width 0.1524)
				(type default)
			)
			(layer "F.SilkS")
		)
		(fp_line
			(start 0.7874 -0.4064)
			(end 0.7874 0.4064)
			(stroke
				(width 0.1524)
				(type default)
			)
			(layer "F.SilkS")
		)
		(fp_line
			(start -0.7874 0.4064)
			(end -0.7874 -0.4064)
			(stroke
				(width 0.1524)
				(type default)
			)
			(layer "F.SilkS")
		)
		(fp_line
			(start -0.7874 -0.4064)
			(end 0.7874 -0.4064)
			(stroke
				(width 0.1524)
				(type default)
			)
			(layer "F.SilkS")
		)
		(fp_line
			(start 0.67945 0.3048)
			(end 0.120396 0.3048)
			(stroke
				(width 0.1)
				(type default)
			)
			(layer "F.Fab")
		)
		(fp_line
			(start 0.67945 -0.3048)
			(end 0.67945 0.3048)
			(stroke
				(width 0.1)
				(type default)
			)
			(layer "F.Fab")
		)
		(fp_line
			(start 0.12065 -0.2794)
			(end 0.12065 -0.3048)
			(stroke
				(width 0.1)
				(type default)
			)
			(layer "F.Fab")
		)
		(fp_line
			(start 0.12065 -0.3048)
			(end 0.67945 -0.3048)
			(stroke
				(width 0.1)
				(type default)
			)
			(layer "F.Fab")
		)
		(fp_line
			(start 0.120396 0.3048)
			(end 0.120396 0.2794)
			(stroke
				(width 0.1)
				(type default)
			)
			(layer "F.Fab")
		)
		(fp_line
			(start 0.120396 0.2794)
			(end -0.12065 0.2794)
			(stroke
				(width 0.1)
				(type default)
			)
			(layer "F.Fab")
		)
		(fp_line
			(start -0.12065 0.3048)
			(end -0.67945 0.3048)
			(stroke
				(width 0.1)
				(type default)
			)
			(layer "F.Fab")
		)
		(fp_line
			(start -0.12065 0.2794)
			(end -0.12065 0.3048)
			(stroke
				(width 0.1)
				(type default)
			)
			(layer "F.Fab")
		)
		(fp_line
			(start -0.12065 -0.2794)
			(end 0.12065 -0.2794)
			(stroke
				(width 0.1)
				(type default)
			)
			(layer "F.Fab")
		)
		(fp_line
			(start -0.12065 -0.305054)
			(end -0.12065 -0.2794)
			(stroke
				(width 0.1)
				(type default)
			)
			(layer "F.Fab")
		)
		(fp_line
			(start -0.67945 0.3048)
			(end -0.67945 -0.305054)
			(stroke
				(width 0.1)
				(type default)
			)
			(layer "F.Fab")
		)
		(fp_line
			(start -0.67945 -0.305054)
			(end -0.12065 -0.305054)
			(stroke
				(width 0.1)
				(type default)
			)
			(layer "F.Fab")
		)
		(pad "1" smd circle
			(at -0.40005 0 180)
			(size 0 0)
			(layers "F.Cu" "F.Mask" "F.Paste")
			(net "SSD13_PEX_PWR_EN")
		)
		(pad "2" smd circle
			(at 0.40005 0 180)
			(size 0 0)
			(layers "F.Cu" "F.Mask" "F.Paste")
			(net "SSD13_PEX_PWR_EN_R")
		)
	)
)
